(kicad_pcb
	(version 20260206)
	(generator "pcbnew")
	(generator_version "10.0")
	(general
		(thickness 1.6)
		(legacy_teardrops no)
	)
	(paper "A4")
	(title_block
		(title "Wiwynn_Tioga_Pass_MB.brd")
		(comment 1 "Tioga Pass / footprints 889-893 of 4770")
	)
	(layers
		(0 "F.Cu" signal "TOP")
		(4 "In1.Cu" signal "L2GND")
		(6 "In2.Cu" signal "L3")
		(8 "In3.Cu" signal "L4GND")
		(10 "In4.Cu" signal "L5")
		(12 "In5.Cu" signal "L6GND")
		(14 "In6.Cu" signal "L7VCC")
		(16 "In7.Cu" signal "L8VCC")
		(18 "In8.Cu" signal "L9GND")
		(20 "In9.Cu" signal "L10")
		(22 "In10.Cu" signal "L11GND")
		(24 "In11.Cu" signal "L12")
		(26 "In12.Cu" signal "L13GND")
		(2 "B.Cu" signal "BOTTOM")
		(9 "F.Adhes" user "F.Adhesive")
		(11 "B.Adhes" user "B.Adhesive")
		(13 "F.Paste" user "Package Geometry/Pastemask Top")
		(15 "B.Paste" user "Package Geometry/Pastemask Bottom")
		(5 "F.SilkS" user "Ref Des/Silkscreen Top")
		(7 "B.SilkS" user "Ref Des/Silkscreen Bottom")
		(1 "F.Mask" user "Board Geometry/Soldermask Top")
		(3 "B.Mask" user "Board Geometry/Soldermask Bottom")
		(17 "Dwgs.User" user "User.Drawings")
		(19 "Cmts.User" user "User.Comments")
		(21 "Eco1.User" user "User.Eco1")
		(23 "Eco2.User" user "User.Eco2")
		(25 "Edge.Cuts" user "Board Geometry/Outline")
		(27 "Margin" user)
		(31 "F.CrtYd" user "Package Geometry/Place Bound Top")
		(29 "B.CrtYd" user "Package Geometry/Place Bound Bottom")
		(35 "F.Fab" user "Ref Des/Assembly Top")
		(33 "B.Fab" user "Ref Des/Assembly Bottom")
	)
	(footprint ""
		(layer "F.Cu")
		(at 169.0878 -74.93 90)
		(property "Reference" "C4D22"
			(at 0 0 90)
			(layer "F.SilkS")
			(hide yes)
			(effects
				(font
					(size 1.27 1.27)
				)
			)
		)
		(property "Value" ""
			(at 0 0 90)
			(layer "F.Fab")
			(effects
				(font
					(size 1.27 1.27)
				)
			)
		)
		(duplicate_pad_numbers_are_jumpers no)
		(fp_poly
			(pts
				(xy 0.3048 -0.1016) (xy 0.3048 0.9906) (xy -0.3048 0.9906) (xy -0.3048 -0.1016)
			)
			(stroke
				(width 0)
				(type default)
			)
			(fill no)
			(layer "F.CrtYd")
		)
		(fp_line
			(start 0.3048 -0.1016)
			(end -0.3048 -0.1016)
			(stroke
				(width 0.1)
				(type default)
			)
			(layer "F.Fab")
		)
		(fp_line
			(start -0.3048 -0.1016)
			(end -0.3048 0.9906)
			(stroke
				(width 0.1)
				(type default)
			)
			(layer "F.Fab")
		)
		(fp_line
			(start 0.3048 0.9906)
			(end 0.3048 -0.1016)
			(stroke
				(width 0.1)
				(type default)
			)
			(layer "F.Fab")
		)
		(fp_line
			(start -0.3048 0.9906)
			(end 0.3048 0.9906)
			(stroke
				(width 0.1)
				(type default)
			)
			(layer "F.Fab")
		)
		(pad "1" smd rect
			(at 0 0 90)
			(size 0.508 0.508)
			(layers "F.Cu" "F.Mask" "F.Paste")
			(net "P3V3_DB1200_R")
		)
		(pad "2" smd rect
			(at 0 0.889 90)
			(size 0.508 0.508)
			(layers "F.Cu" "F.Mask" "F.Paste")
			(net "GND")
		)
		(zone
			(layer "F.Cu")
			(hatch none 0.5)
			(connect_pads
				(clearance 0)
			)
			(min_thickness 0.25)
			(keepout
				(tracks allowed)
				(vias not_allowed)
				(pads allowed)
				(copperpour not_allowed)
				(footprints allowed)
			)
			(placement
				(enabled no)
				(sheetname "")
			)
			(fill
				(thermal_gap 0.5)
				(thermal_bridge_width 0.5)
				(island_removal_mode 0)
			)
			(polygon
				(pts
					(xy 169.3418 -74.676) (xy 169.3418 -75.184) (xy 169.7228 -75.184) (xy 169.7228 -74.676)
				)
			)
		)
		(zone
			(layer "F.Cu")
			(hatch none 0.5)
			(connect_pads
				(clearance 0)
			)
			(min_thickness 0.25)
			(keepout
				(tracks not_allowed)
				(vias allowed)
				(pads allowed)
				(copperpour not_allowed)
				(footprints allowed)
			)
			(placement
				(enabled no)
				(sheetname "")
			)
			(fill
				(thermal_gap 0.5)
				(thermal_bridge_width 0.5)
				(island_removal_mode 0)
			)
			(polygon
				(pts
					(xy 169.7228 -74.676) (xy 169.7228 -75.184) (xy 169.3418 -75.184) (xy 169.3418 -74.676)
				)
			)
		)
	)
	(footprint ""
		(layer "F.Cu")
		(at 24.728932 -61.0362 -90)
		(property "Reference" "R1E1"
			(at 0 0 270)
			(layer "F.SilkS")
			(hide yes)
			(effects
				(font
					(size 1.27 1.27)
				)
			)
		)
		(property "Value" ""
			(at 0 0 270)
			(layer "F.Fab")
			(effects
				(font
					(size 1.27 1.27)
				)
			)
		)
		(duplicate_pad_numbers_are_jumpers no)
		(fp_rect
			(start 0.2794 -0.1016)
			(end -0.2794 0.9906)
			(stroke
				(width 0)
				(type default)
			)
			(fill no)
			(layer "F.CrtYd")
		)
		(fp_line
			(start -0.2794 0.9906)
			(end 0.2794 0.9906)
			(stroke
				(width 0.1)
				(type default)
			)
			(layer "F.Fab")
		)
		(fp_line
			(start 0.2794 0.9906)
			(end 0.2794 -0.1016)
			(stroke
				(width 0.1)
				(type default)
			)
			(layer "F.Fab")
		)
		(fp_line
			(start -0.2794 -0.1016)
			(end -0.2794 0.9906)
			(stroke
				(width 0.1)
				(type default)
			)
			(layer "F.Fab")
		)
		(fp_line
			(start 0.2794 -0.1016)
			(end -0.2794 -0.1016)
			(stroke
				(width 0.1)
				(type default)
			)
			(layer "F.Fab")
		)
		(pad "1" smd rect
			(at 0 0 270)
			(size 0.508 0.508)
			(layers "F.Cu" "F.Mask" "F.Paste")
			(net "A_HSC_GATE")
		)
		(pad "2" smd rect
			(at 0 0.889 270)
			(size 0.508 0.508)
			(layers "F.Cu" "F.Mask" "F.Paste")
			(net "A_HSC_GATE1_R")
		)
		(zone
			(layer "F.Cu")
			(hatch none 0.5)
			(connect_pads
				(clearance 0)
			)
			(min_thickness 0.25)
			(keepout
				(tracks not_allowed)
				(vias allowed)
				(pads allowed)
				(copperpour not_allowed)
				(footprints allowed)
			)
			(placement
				(enabled no)
				(sheetname "")
			)
			(fill
				(thermal_gap 0.5)
				(thermal_bridge_width 0.5)
				(island_removal_mode 0)
			)
			(polygon
				(pts
					(xy 24.474932 -60.7822) (xy 24.474932 -61.2902) (xy 24.093932 -61.2902) (xy 24.093932 -60.7822)
				)
			)
		)
		(zone
			(layer "F.Cu")
			(hatch none 0.5)
			(connect_pads
				(clearance 0)
			)
			(min_thickness 0.25)
			(keepout
				(tracks allowed)
				(vias not_allowed)
				(pads allowed)
				(copperpour not_allowed)
				(footprints allowed)
			)
			(placement
				(enabled no)
				(sheetname "")
			)
			(fill
				(thermal_gap 0.5)
				(thermal_bridge_width 0.5)
				(island_removal_mode 0)
			)
			(polygon
				(pts
					(xy 24.474932 -60.7822) (xy 24.474932 -61.2902) (xy 24.093932 -61.2902) (xy 24.093932 -60.7822)
				)
			)
		)
	)
	(footprint ""
		(layer "F.Cu")
		(at 462.19491 -157.140402 180)
		(property "Reference" "J8D4"
			(at 0 0 180)
			(layer "F.SilkS")
			(hide yes)
			(effects
				(font
					(size 1.27 1.27)
				)
			)
		)
		(property "Value" "*"
			(at -5.103876 -0.820166 180)
			(unlocked yes)
			(layer "F.Fab")
			(hide yes)
			(effects
				(font
					(size 1.27 1.016)
					(thickness 0.1524)
				)
			)
		)
		(property "Device Type" "PIN-CON3-27-GP_CONN-G7-PIN-CONA"
			(at -5.103876 -2.344166 180)
			(unlocked yes)
			(layer "F.Fab")
			(hide yes)
			(effects
				(font
					(size 1.27 1.016)
					(thickness 0.1524)
				)
			)
		)
		(duplicate_pad_numbers_are_jumpers no)
		(fp_line
			(start 3.937 1.4986)
			(end -3.937 1.4986)
			(stroke
				(width 0.1524)
				(type default)
			)
			(layer "F.SilkS")
		)
		(fp_line
			(start 3.937 -1.4986)
			(end 3.937 1.4986)
			(stroke
				(width 0.1524)
				(type default)
			)
			(layer "F.SilkS")
		)
		(fp_line
			(start -2.794 -1.6256)
			(end -4.064 -1.6256)
			(stroke
				(width 0.4064)
				(type default)
			)
			(layer "F.SilkS")
		)
		(fp_line
			(start -3.937 1.4986)
			(end -3.937 -1.4986)
			(stroke
				(width 0.1524)
				(type default)
			)
			(layer "F.SilkS")
		)
		(fp_line
			(start -3.937 -1.4986)
			(end 3.937 -1.4986)
			(stroke
				(width 0.1524)
				(type default)
			)
			(layer "F.SilkS")
		)
		(fp_line
			(start -4.064 -1.6256)
			(end -4.064 -0.3556)
			(stroke
				(width 0.4064)
				(type default)
			)
			(layer "F.SilkS")
		)
		(fp_circle
			(center 2.54 0)
			(end 1.4732 0)
			(stroke
				(width 0.3048)
				(type default)
			)
			(fill no)
			(layer "F.SilkS")
		)
		(fp_circle
			(center 0 0)
			(end -1.0668 0)
			(stroke
				(width 0.3048)
				(type default)
			)
			(fill no)
			(layer "F.SilkS")
		)
		(fp_circle
			(center -2.54 0)
			(end -3.6068 0)
			(stroke
				(width 0.3048)
				(type default)
			)
			(fill no)
			(layer "F.SilkS")
		)
		(fp_rect
			(start -3.683 1.2446)
			(end 3.683 -1.2446)
			(stroke
				(width 0)
				(type default)
			)
			(fill no)
			(layer "F.CrtYd")
		)
		(fp_poly
			(pts
				(xy -4.191 1.7526) (xy -4.191 -1.7526) (xy 4.191 -1.7526) (xy 4.191 1.7526) (xy 0.00254 1.7526)
				(xy 0.00254 1.2446) (xy 3.683 1.2446) (xy 3.683 -1.2446) (xy -3.683 -1.2446) (xy -3.683 1.2446)
				(xy -0.00254 1.2446) (xy -0.00254 1.7526)
			)
			(stroke
				(width 0)
				(type default)
			)
			(fill no)
			(layer "F.CrtYd")
		)
		(fp_rect
			(start -4.191 1.7526)
			(end 4.191 -1.7526)
			(stroke
				(width 0)
				(type default)
			)
			(fill no)
			(layer "F.Fab")
		)
		(pad "1" thru_hole circle
			(at -2.54 0 180)
			(size 1.4224 1.4224)
			(drill 1.016)
			(layers "*.Cu" "*.Mask")
			(remove_unused_layers no)
			(net "SMB_VR_STBY_LVC3_SDA")
			(clearance 0.1524)
			(thermal_gap 0.1524)
		)
		(pad "2" thru_hole circle
			(at 0 0 180)
			(size 1.4224 1.4224)
			(drill 1.016)
			(layers "*.Cu" "*.Mask")
			(remove_unused_layers no)
			(net "GND")
			(clearance 0.1524)
			(thermal_gap 0.1524)
		)
		(pad "3" thru_hole circle
			(at 2.54 0 180)
			(size 1.4224 1.4224)
			(drill 1.016)
			(layers "*.Cu" "*.Mask")
			(remove_unused_layers no)
			(net "SMB_VR_STBY_LVC3_SCL")
			(clearance 0.1524)
			(thermal_gap 0.1524)
		)
	)
	(footprint ""
		(layer "F.Cu")
		(at 276.000464 -149.8092 90)
		(property "Reference" "C5A9"
			(at 1.848866 0.752348 90)
			(unlocked yes)
			(layer "F.SilkS")
			(effects
				(font
					(size 1.27 0.9652)
					(thickness 0.1524)
				)
			)
		)
		(property "Value" ""
			(at 0 0 90)
			(layer "F.Fab")
			(effects
				(font
					(size 1.27 1.27)
				)
			)
		)
		(duplicate_pad_numbers_are_jumpers no)
		(fp_rect
			(start -0.500126 1.598422)
			(end 0.500126 -0.201422)
			(stroke
				(width 0)
				(type default)
			)
			(fill no)
			(layer "F.CrtYd")
		)
		(fp_line
			(start 0.500126 -0.201422)
			(end 0.500126 1.598422)
			(stroke
				(width 0.1)
				(type default)
			)
			(layer "F.Fab")
		)
		(fp_line
			(start -0.500126 -0.201422)
			(end 0.500126 -0.201422)
			(stroke
				(width 0.1)
				(type default)
			)
			(layer "F.Fab")
		)
		(fp_line
			(start 0.500126 1.598422)
			(end -0.500126 1.598422)
			(stroke
				(width 0.1)
				(type default)
			)
			(layer "F.Fab")
		)
		(fp_line
			(start -0.500126 1.598422)
			(end -0.500126 -0.201422)
			(stroke
				(width 0.1)
				(type default)
			)
			(layer "F.Fab")
		)
		(pad "1" smd rect
			(at 0 0)
			(size 0.889 0.9906)
			(layers "F.Cu" "F.Mask" "F.Paste")
			(net "PVDDQ_DEF")
		)
		(pad "2" smd rect
			(at 0 1.397)
			(size 0.889 0.9906)
			(layers "F.Cu" "F.Mask" "F.Paste")
			(net "GND")
		)
		(zone
			(layer "F.Cu")
			(hatch none 0.5)
			(connect_pads
				(clearance 0)
			)
			(min_thickness 0.25)
			(keepout
				(tracks allowed)
				(vias not_allowed)
				(pads allowed)
				(copperpour not_allowed)
				(footprints allowed)
			)
			(placement
				(enabled no)
				(sheetname "")
			)
			(fill
				(thermal_gap 0.5)
				(thermal_bridge_width 0.5)
				(island_removal_mode 0)
			)
			(polygon
				(pts
					(xy 276.952964 -149.3139) (xy 276.952964 -150.3045) (xy 276.444964 -150.3045) (xy 276.444964 -149.3139)
				)
			)
		)
		(zone
			(layer "F.Cu")
			(hatch none 0.5)
			(connect_pads
				(clearance 0)
			)
			(min_thickness 0.25)
			(keepout
				(tracks not_allowed)
				(vias allowed)
				(pads allowed)
				(copperpour not_allowed)
				(footprints allowed)
			)
			(placement
				(enabled no)
				(sheetname "")
			)
			(fill
				(thermal_gap 0.5)
				(thermal_bridge_width 0.5)
				(island_removal_mode 0)
			)
			(polygon
				(pts
					(xy 276.952964 -149.3139) (xy 276.952964 -150.3045) (xy 276.444964 -150.3045) (xy 276.444964 -149.3139)
				)
			)
		)
	)
	(footprint ""
		(layer "F.Cu")
		(at 370.967 -152.019 90)
		(property "Reference" "C22W22"
			(at 0 0 90)
			(layer "F.SilkS")
			(hide yes)
			(effects
				(font
					(size 1.27 1.27)
				)
			)
		)
		(property "Value" "*"
			(at -0.0762 -6.2357 90)
			(unlocked yes)
			(layer "F.Fab")
			(hide yes)
			(effects
				(font
					(size 1.27 1.016)
					(thickness 0.1524)
				)
			)
		)
		(property "Device Type" "SC22U16V5MX-4-GP_SMD-BCG5-SC22A"
			(at -0.0762 -8.2677 90)
			(unlocked yes)
			(layer "F.Fab")
			(hide yes)
			(effects
				(font
					(size 1.27 1.016)
					(thickness 0.1524)
				)
			)
		)
		(duplicate_pad_numbers_are_jumpers no)
		(fp_line
			(start 0.635 0)
			(end -0.635 0)
			(stroke
				(width 0.508)
				(type default)
			)
			(layer "F.SilkS")
		)
		(fp_rect
			(start -0.9652 1.778)
			(end 0.9652 -1.778)
			(stroke
				(width 0)
				(type default)
			)
			(fill no)
			(layer "F.CrtYd")
		)
		(fp_poly
			(pts
				(xy -0.9652 -1.778) (xy 0.9652 -1.778) (xy 0.9652 1.778) (xy -0.9652 1.778)
			)
			(stroke
				(width 0)
				(type default)
			)
			(fill no)
			(layer "F.Fab")
		)
		(pad "1" smd rect
			(at 0 -0.9652 90)
			(size 1.397 1.143)
			(layers "F.Cu" "F.Mask" "F.Paste")
			(net "VR_FET_SW_P12V_STBY_PVDDQ_DEF")
		)
		(pad "2" smd rect
			(at 0 0.9652 90)
			(size 1.397 1.143)
			(layers "F.Cu" "F.Mask" "F.Paste")
			(net "GND")
		)
	)
)
